(kicad_pcb
	(version 20260206)
	(generator "pcbnew")
	(generator_version "10.0")
	(general
		(thickness 1.6)
		(legacy_teardrops no)
	)
	(paper "A4")
	(title_block
		(title "Bryce Canyon_F.DPB_16315-1-OCP.brd")
		(comment 1 "Bryce Canyon / footprints 1864-1870 of 2223")
	)
	(layers
		(0 "F.Cu" signal "TOP")
		(4 "In1.Cu" signal "L2GND")
		(6 "In2.Cu" signal "L3")
		(8 "In3.Cu" signal "L4GND")
		(10 "In4.Cu" signal "L5")
		(12 "In5.Cu" signal "L6VCC")
		(14 "In6.Cu" signal "L7VCC")
		(16 "In7.Cu" signal "L8")
		(18 "In8.Cu" signal "L9GND")
		(20 "In9.Cu" signal "L10")
		(22 "In10.Cu" signal "L11GND")
		(2 "B.Cu" signal "BOTTOM")
		(9 "F.Adhes" user "F.Adhesive")
		(11 "B.Adhes" user "B.Adhesive")
		(13 "F.Paste" user "Package Geometry/Pastemask Top")
		(15 "B.Paste" user "Package Geometry/Pastemask Bottom")
		(5 "F.SilkS" user "Ref Des/Silkscreen Top")
		(7 "B.SilkS" user "Ref Des/Silkscreen Bottom")
		(1 "F.Mask" user "Board Geometry/Soldermask Top")
		(3 "B.Mask" user "Board Geometry/Soldermask Bottom")
		(17 "Dwgs.User" user "User.Drawings")
		(19 "Cmts.User" user "User.Comments")
		(21 "Eco1.User" user "User.Eco1")
		(23 "Eco2.User" user "User.Eco2")
		(25 "Edge.Cuts" user "Board Geometry/Outline")
		(27 "Margin" user)
		(31 "F.CrtYd" user "Package Geometry/Place Bound Top")
		(29 "B.CrtYd" user "Package Geometry/Place Bound Bottom")
		(35 "F.Fab" user "Ref Des/Assembly Top")
		(33 "B.Fab" user "Ref Des/Assembly Bottom")
	)
	(footprint ""
		(layer "F.Cu")
		(at 136.367266 -142.628874 -90)
		(property "Reference" "R1046"
			(at 0 0 270)
			(layer "F.SilkS")
			(hide yes)
			(effects
				(font
					(size 1.27 1.27)
				)
			)
		)
		(property "Value" "0R0603-PAD-2-GP-U"
			(at 2.1209 -0.1397 270)
			(unlocked yes)
			(layer "F.Fab")
			(hide yes)
			(effects
				(font
					(size 1.016 1.016)
					(thickness 0.1524)
				)
			)
		)
		(property "Device Type" "0R0603-PAD-1-U"
			(at 2.1209 -1.6637 270)
			(unlocked yes)
			(layer "F.Fab")
			(hide yes)
			(effects
				(font
					(size 1.016 1.016)
					(thickness 0.1524)
				)
			)
		)
		(duplicate_pad_numbers_are_jumpers no)
		(fp_rect
			(start -0.5842 1.3335)
			(end 0.5842 -1.3335)
			(stroke
				(width 0)
				(type default)
			)
			(fill no)
			(layer "F.CrtYd")
		)
		(fp_rect
			(start -0.5842 1.3335)
			(end 0.5842 -1.3335)
			(stroke
				(width 0)
				(type default)
			)
			(fill no)
			(layer "F.Fab")
		)
		(pad "1" smd custom
			(at 0 -0.762 270)
			(size 0.2159 0.2159)
			(layers "F.Cu" "F.Mask" "F.Paste")
			(net "AGND_CURRENT_MONOA")
			(options
				(clearance outline)
				(anchor circle)
			)
			(primitives
				(gr_poly
					(pts
						(arc
							(start -0.3302 -0.5842)
							(mid -0.402042 -0.554442)
							(end -0.4318 -0.4826)
						)
						(arc
							(start -0.4318 0.4826)
							(mid -0.402042 0.554442)
							(end -0.3302 0.5842)
						)
						(arc
							(start 0.3302 0.5842)
							(mid 0.402042 0.554442)
							(end 0.4318 0.4826)
						)
						(arc
							(start 0.4318 -0.4826)
							(mid 0.402042 -0.554442)
							(end 0.3302 -0.5842)
						)
					)
					(width 0)
					(fill yes)
				)
			)
		)
		(pad "2" smd custom
			(at 0 0.762 270)
			(size 0.2159 0.2159)
			(layers "F.Cu" "F.Mask" "F.Paste")
			(net "GND")
			(options
				(clearance outline)
				(anchor circle)
			)
			(primitives
				(gr_poly
					(pts
						(arc
							(start -0.4318 0.4826)
							(mid -0.402042 0.554442)
							(end -0.3302 0.5842)
						)
						(arc
							(start 0.3302 0.5842)
							(mid 0.402042 0.554442)
							(end 0.4318 0.4826)
						)
						(arc
							(start 0.4318 -0.4826)
							(mid 0.402042 -0.554442)
							(end 0.3302 -0.5842)
						)
						(arc
							(start -0.3302 -0.5842)
							(mid -0.402042 -0.554442)
							(end -0.4318 -0.4826)
						)
					)
					(width 0)
					(fill yes)
				)
			)
		)
	)
	(footprint ""
		(layer "F.Cu")
		(at 463.0039 -177.016918)
		(property "Reference" "Q134"
			(at 0 0 0)
			(layer "F.SilkS")
			(hide yes)
			(effects
				(font
					(size 1.27 1.27)
				)
			)
		)
		(property "Value" "AO4407AL-GP"
			(at -3.707384 -1.5367 0)
			(unlocked yes)
			(layer "F.Fab")
			(hide yes)
			(effects
				(font
					(size 1.016 1.016)
					(thickness 0.1524)
				)
			)
		)
		(property "Device Type" "SOIC8H69"
			(at -3.707384 -3.0607 0)
			(unlocked yes)
			(layer "F.Fab")
			(hide yes)
			(effects
				(font
					(size 1.016 1.016)
					(thickness 0.1524)
				)
			)
		)
		(duplicate_pad_numbers_are_jumpers no)
		(fp_line
			(start -2.7432 -1.4224)
			(end -2.7432 1.4224)
			(stroke
				(width 0.1524)
				(type default)
			)
			(layer "F.SilkS")
		)
		(fp_line
			(start -2.7432 1.4224)
			(end -2.6416 1.4224)
			(stroke
				(width 0.1524)
				(type default)
			)
			(layer "F.SilkS")
		)
		(fp_line
			(start -2.7432 1.4224)
			(end 2.1336 1.4224)
			(stroke
				(width 0.1524)
				(type default)
			)
			(layer "F.SilkS")
		)
		(fp_line
			(start -2.7178 -0.508)
			(end -2.1844 -0.0508)
			(stroke
				(width 0.1524)
				(type default)
			)
			(layer "F.SilkS")
		)
		(fp_line
			(start -2.6289 3.4417)
			(end -2.6289 1.4732)
			(stroke
				(width 0.381)
				(type default)
			)
			(layer "F.SilkS")
		)
		(fp_line
			(start -2.1844 -0.0508)
			(end -2.7178 0.508)
			(stroke
				(width 0.1524)
				(type default)
			)
			(layer "F.SilkS")
		)
		(fp_line
			(start 2.1336 -1.4224)
			(end -2.7432 -1.4224)
			(stroke
				(width 0.1524)
				(type default)
			)
			(layer "F.SilkS")
		)
		(fp_line
			(start 2.1336 1.4224)
			(end 2.1336 -1.4224)
			(stroke
				(width 0.1524)
				(type default)
			)
			(layer "F.SilkS")
		)
		(fp_poly
			(pts
				(xy -2.2098 -1.4224) (xy -2.2098 1.4224) (xy 2.2098 1.4224) (xy 2.2098 -1.4224)
			)
			(stroke
				(width 0)
				(type default)
			)
			(fill yes)
			(layer "F.SilkS")
		)
		(fp_rect
			(start -2.450084 2.999994)
			(end 2.450084 -2.999994)
			(stroke
				(width 0)
				(type default)
			)
			(fill no)
			(layer "F.CrtYd")
		)
		(fp_poly
			(pts
				(xy -2.8194 3.6322) (xy -2.8194 -3.6322) (xy 2.8194 -3.6322) (xy 2.8194 1.18364) (xy 2.450084 1.18364)
				(xy 2.450084 -2.999994) (xy -2.450084 -2.999994) (xy -2.450084 2.999994) (xy 2.450084 2.999994)
				(xy 2.450084 1.18618) (xy 2.8194 1.18618) (xy 2.8194 3.6322)
			)
			(stroke
				(width 0)
				(type default)
			)
			(fill no)
			(layer "F.CrtYd")
		)
		(fp_rect
			(start -2.8194 3.6322)
			(end 2.8194 -3.6322)
			(stroke
				(width 0)
				(type default)
			)
			(fill no)
			(layer "F.Fab")
		)
		(pad "1" smd rect
			(at -1.905 2.54)
			(size 0.635 1.651)
			(layers "F.Cu" "F.Mask" "F.Paste")
			(net "P12V_A")
		)
		(pad "2" smd rect
			(at -0.635 2.54)
			(size 0.635 1.651)
			(layers "F.Cu" "F.Mask" "F.Paste")
			(net "P12V_A")
		)
		(pad "3" smd rect
			(at 0.635 2.54)
			(size 0.635 1.651)
			(layers "F.Cu" "F.Mask" "F.Paste")
			(net "P12V_A")
		)
		(pad "4" smd rect
			(at 1.905 2.54)
			(size 0.635 1.651)
			(layers "F.Cu" "F.Mask" "F.Paste")
			(net "SW_HDD_N22")
		)
		(pad "5" smd rect
			(at 1.905 -2.54)
			(size 0.635 1.651)
			(layers "F.Cu" "F.Mask" "F.Paste")
			(net "P12V_HDD22")
		)
		(pad "6" smd rect
			(at 0.635 -2.54)
			(size 0.635 1.651)
			(layers "F.Cu" "F.Mask" "F.Paste")
			(net "P12V_HDD22")
		)
		(pad "7" smd rect
			(at -0.635 -2.54)
			(size 0.635 1.651)
			(layers "F.Cu" "F.Mask" "F.Paste")
			(net "P12V_HDD22")
		)
		(pad "8" smd rect
			(at -1.905 -2.54)
			(size 0.635 1.651)
			(layers "F.Cu" "F.Mask" "F.Paste")
			(net "P12V_HDD22")
		)
	)
	(footprint ""
		(layer "F.Cu")
		(at 469.747854 -127.756666 180)
		(property "Reference" "Q250"
			(at 0 0 180)
			(layer "F.SilkS")
			(hide yes)
			(effects
				(font
					(size 1.27 1.27)
				)
			)
		)
		(property "Value" "2N7002K-2-GP"
			(at 0.127 -8.9662 180)
			(unlocked yes)
			(layer "F.Fab")
			(hide yes)
			(effects
				(font
					(size 1.016 1.016)
					(thickness 0.1524)
				)
			)
		)
		(property "Device Type" "SOT23DGS2D4H44"
			(at 0.127 -10.4902 180)
			(unlocked yes)
			(layer "F.Fab")
			(hide yes)
			(effects
				(font
					(size 1.016 1.016)
					(thickness 0.1524)
				)
			)
		)
		(duplicate_pad_numbers_are_jumpers no)
		(fp_line
			(start 1.651 1.778)
			(end 1.651 -1.778)
			(stroke
				(width 0.1524)
				(type default)
			)
			(layer "F.SilkS")
		)
		(fp_line
			(start 1.651 -1.778)
			(end -1.651 -1.778)
			(stroke
				(width 0.1524)
				(type default)
			)
			(layer "F.SilkS")
		)
		(fp_line
			(start -1.651 1.778)
			(end 1.651 1.778)
			(stroke
				(width 0.1524)
				(type default)
			)
			(layer "F.SilkS")
		)
		(fp_line
			(start -1.651 -1.778)
			(end -1.651 1.778)
			(stroke
				(width 0.1524)
				(type default)
			)
			(layer "F.SilkS")
		)
		(fp_poly
			(pts
				(xy -1.778 1.8796) (xy -1.778 -1.8796) (xy 1.778 -1.8796) (xy 1.778 1.8796)
			)
			(stroke
				(width 0)
				(type default)
			)
			(fill no)
			(layer "F.CrtYd")
		)
		(fp_poly
			(pts
				(xy -1.778 1.8796) (xy -1.778 -1.8796) (xy 1.778 -1.8796) (xy 1.778 1.8796)
			)
			(stroke
				(width 0)
				(type default)
			)
			(fill no)
			(layer "F.Fab")
		)
		(pad "D" smd custom
			(at 0 -0.9525 180)
			(size 0.1905 0.1905)
			(layers "F.Cu" "F.Mask" "F.Paste")
			(net "FLT_HDD23_N")
			(options
				(clearance outline)
				(anchor circle)
			)
			(primitives
				(gr_poly
					(pts
						(arc
							(start -0.1778 0.5715)
							(mid -0.321484 0.511984)
							(end -0.381 0.3683)
						)
						(arc
							(start -0.381 -0.3683)
							(mid -0.321484 -0.511984)
							(end -0.1778 -0.5715)
						)
						(arc
							(start 0.1778 -0.5715)
							(mid 0.321484 -0.511984)
							(end 0.381 -0.3683)
						)
						(arc
							(start 0.381 0.3683)
							(mid 0.321484 0.511984)
							(end 0.1778 0.5715)
						)
					)
					(width 0)
					(fill yes)
				)
			)
		)
		(pad "G" smd custom
			(at -0.98425 0.9525 180)
			(size 0.1905 0.1905)
			(layers "F.Cu" "F.Mask" "F.Paste")
			(net "DRIVE_A_23_FLT_LED")
			(options
				(clearance outline)
				(anchor circle)
			)
			(primitives
				(gr_poly
					(pts
						(arc
							(start -0.1778 0.5715)
							(mid -0.321484 0.511984)
							(end -0.381 0.3683)
						)
						(arc
							(start -0.381 -0.3683)
							(mid -0.321484 -0.511984)
							(end -0.1778 -0.5715)
						)
						(arc
							(start 0.1778 -0.5715)
							(mid 0.321484 -0.511984)
							(end 0.381 -0.3683)
						)
						(arc
							(start 0.381 0.3683)
							(mid 0.321484 0.511984)
							(end 0.1778 0.5715)
						)
					)
					(width 0)
					(fill yes)
				)
			)
		)
		(pad "S" smd custom
			(at 0.98425 0.9525 180)
			(size 0.1905 0.1905)
			(layers "F.Cu" "F.Mask" "F.Paste")
			(net "GND")
			(options
				(clearance outline)
				(anchor circle)
			)
			(primitives
				(gr_poly
					(pts
						(arc
							(start -0.1778 0.5715)
							(mid -0.321484 0.511984)
							(end -0.381 0.3683)
						)
						(arc
							(start -0.381 -0.3683)
							(mid -0.321484 -0.511984)
							(end -0.1778 -0.5715)
						)
						(arc
							(start 0.1778 -0.5715)
							(mid 0.321484 -0.511984)
							(end 0.381 -0.3683)
						)
						(arc
							(start 0.381 0.3683)
							(mid 0.321484 0.511984)
							(end 0.1778 0.5715)
						)
					)
					(width 0)
					(fill yes)
				)
			)
		)
	)
	(footprint ""
		(layer "F.Cu")
		(at 255.411478 -12.667234 180)
		(property "Reference" "TP219"
			(at 0 0 180)
			(layer "F.SilkS")
			(hide yes)
			(effects
				(font
					(size 1.27 1.27)
				)
			)
		)
		(property "Value" "TPAD32-GP"
			(at -0.0508 -1.6764 180)
			(unlocked yes)
			(layer "F.Fab")
			(hide yes)
			(effects
				(font
					(size 1.016 1.016)
					(thickness 0.1524)
				)
			)
		)
		(property "Device Type" "TPAD32"
			(at -0.0508 -3.2004 180)
			(unlocked yes)
			(layer "F.Fab")
			(hide yes)
			(effects
				(font
					(size 1.016 1.016)
					(thickness 0.1524)
				)
			)
		)
		(duplicate_pad_numbers_are_jumpers no)
		(fp_poly
			(pts
				(arc
					(start -0.4064 0)
					(mid 0.4064 0)
					(end -0.4064 0)
				)
			)
			(stroke
				(width 0)
				(type default)
			)
			(fill no)
			(layer "F.CrtYd")
		)
		(fp_poly
			(pts
				(arc
					(start -0.7112 0)
					(mid 0.7112 0)
					(end -0.7112 0)
				)
			)
			(stroke
				(width 0)
				(type default)
			)
			(fill no)
			(layer "F.Fab")
		)
		(pad "1" smd circle
			(at 0 0 180)
			(size 0.8128 0.8128)
			(layers "F.Cu" "F.Mask" "F.Paste")
			(net "TP_COMP_A_NCSI_RXER")
		)
	)
	(footprint ""
		(layer "F.Cu")
		(at 458.9399 -48.554894 -90)
		(property "Reference" "R919"
			(at 0 0 270)
			(layer "F.SilkS")
			(hide yes)
			(effects
				(font
					(size 1.27 1.27)
				)
			)
		)
		(property "Value" "4K7R2J-2-GP"
			(at 0.064008 -3.993896 270)
			(unlocked yes)
			(layer "F.Fab")
			(hide yes)
			(effects
				(font
					(size 1.016 1.016)
					(thickness 0.1524)
				)
			)
		)
		(property "Device Type" "R402H16"
			(at 0.064008 -5.517896 270)
			(unlocked yes)
			(layer "F.Fab")
			(hide yes)
			(effects
				(font
					(size 1.016 1.016)
					(thickness 0.1524)
				)
			)
		)
		(duplicate_pad_numbers_are_jumpers no)
		(fp_line
			(start -0.508 -0.9398)
			(end -0.508 0.9398)
			(stroke
				(width 0.1524)
				(type default)
			)
			(layer "F.SilkS")
		)
		(fp_line
			(start 0.508 -0.9398)
			(end -0.508 -0.9398)
			(stroke
				(width 0.1524)
				(type default)
			)
			(layer "F.SilkS")
		)
		(fp_rect
			(start -0.508 0.9398)
			(end 0.508 -0.9398)
			(stroke
				(width 0)
				(type default)
			)
			(fill no)
			(layer "F.CrtYd")
		)
		(fp_rect
			(start -0.508 0.9398)
			(end 0.508 -0.9398)
			(stroke
				(width 0)
				(type default)
			)
			(fill no)
			(layer "F.Fab")
		)
		(pad "1" smd custom
			(at 0 -0.4445 270)
			(size 0.1397 0.1397)
			(layers "F.Cu" "F.Mask" "F.Paste")
			(net "P12V_A")
			(options
				(clearance outline)
				(anchor circle)
			)
			(primitives
				(gr_poly
					(pts
						(arc
							(start -0.1778 -0.2794)
							(mid -0.249642 -0.249642)
							(end -0.2794 -0.1778)
						)
						(arc
							(start -0.2794 0.1778)
							(mid -0.249642 0.249642)
							(end -0.1778 0.2794)
						)
						(arc
							(start 0.1778 0.2794)
							(mid 0.249642 0.249642)
							(end 0.2794 0.1778)
						)
						(arc
							(start 0.2794 -0.1778)
							(mid 0.249642 -0.249642)
							(end 0.1778 -0.2794)
						)
					)
					(width 0)
					(fill yes)
				)
			)
		)
		(pad "2" smd custom
			(at 0 0.4445 270)
			(size 0.1397 0.1397)
			(layers "F.Cu" "F.Mask" "F.Paste")
			(net "SW_HDD_P34")
			(options
				(clearance outline)
				(anchor circle)
			)
			(primitives
				(gr_poly
					(pts
						(arc
							(start -0.1778 -0.2794)
							(mid -0.249642 -0.249642)
							(end -0.2794 -0.1778)
						)
						(arc
							(start -0.2794 0.1778)
							(mid -0.249642 0.249642)
							(end -0.1778 0.2794)
						)
						(arc
							(start 0.1778 0.2794)
							(mid 0.249642 0.249642)
							(end 0.2794 0.1778)
						)
						(arc
							(start 0.2794 -0.1778)
							(mid 0.249642 -0.249642)
							(end 0.1778 -0.2794)
						)
					)
					(width 0)
					(fill yes)
				)
			)
		)
	)
	(footprint ""
		(layer "F.Cu")
		(at 272.321528 -16.425672 -90)
		(property "Reference" "TP249"
			(at 0 0 270)
			(layer "F.SilkS")
			(hide yes)
			(effects
				(font
					(size 1.27 1.27)
				)
			)
		)
		(property "Value" "TPAD32-GP"
			(at -0.0508 -1.6764 270)
			(unlocked yes)
			(layer "F.Fab")
			(hide yes)
			(effects
				(font
					(size 1.016 1.016)
					(thickness 0.1524)
				)
			)
		)
		(property "Device Type" "TPAD32"
			(at -0.0508 -3.2004 270)
			(unlocked yes)
			(layer "F.Fab")
			(hide yes)
			(effects
				(font
					(size 1.016 1.016)
					(thickness 0.1524)
				)
			)
		)
		(duplicate_pad_numbers_are_jumpers no)
		(fp_poly
			(pts
				(arc
					(start 0 -0.4064)
					(mid 0 0.4064)
					(end 0 -0.4064)
				)
			)
			(stroke
				(width 0)
				(type default)
			)
			(fill no)
			(layer "F.CrtYd")
		)
		(fp_poly
			(pts
				(arc
					(start 0 -0.7112)
					(mid 0 0.7112)
					(end 0 -0.7112)
				)
			)
			(stroke
				(width 0)
				(type default)
			)
			(fill no)
			(layer "F.Fab")
		)
		(pad "1" smd circle
			(at 0 0 270)
			(size 0.8128 0.8128)
			(layers "F.Cu" "F.Mask" "F.Paste")
			(net "PCIE_COMP_B_CLK_P5")
		)
	)
	(footprint ""
		(layer "F.Cu")
		(at 392.91895 -304.335942 180)
		(property "Reference" "C151"
			(at 0 0 180)
			(layer "F.SilkS")
			(hide yes)
			(effects
				(font
					(size 1.27 1.27)
				)
			)
		)
		(property "Value" "SC1U25V3KX-GP"
			(at 0 -2.8194 180)
			(unlocked yes)
			(layer "F.Fab")
			(hide yes)
			(effects
				(font
					(size 1.016 1.016)
					(thickness 0.1524)
				)
			)
		)
		(property "Device Type" "C603H36"
			(at 0 -4.3434 180)
			(unlocked yes)
			(layer "F.Fab")
			(hide yes)
			(effects
				(font
					(size 1.016 1.016)
					(thickness 0.1524)
				)
			)
		)
		(duplicate_pad_numbers_are_jumpers no)
		(fp_line
			(start 0.508 0)
			(end -0.508 0)
			(stroke
				(width 0.2032)
				(type default)
			)
			(layer "F.SilkS")
		)
		(fp_rect
			(start -0.5842 1.3335)
			(end 0.5842 -1.3335)
			(stroke
				(width 0)
				(type default)
			)
			(fill no)
			(layer "F.CrtYd")
		)
		(fp_rect
			(start -0.5842 1.3335)
			(end 0.5842 -1.3335)
			(stroke
				(width 0)
				(type default)
			)
			(fill no)
			(layer "F.Fab")
		)
		(pad "1" smd custom
			(at 0 -0.762 180)
			(size 0.2159 0.2159)
			(layers "F.Cu" "F.Mask" "F.Paste")
			(net "P12V_HDD8")
			(options
				(clearance outline)
				(anchor circle)
			)
			(primitives
				(gr_poly
					(pts
						(arc
							(start -0.3302 -0.4318)
							(mid -0.402042 -0.402042)
							(end -0.4318 -0.3302)
						)
						(arc
							(start -0.4318 0.3302)
							(mid -0.402042 0.402042)
							(end -0.3302 0.4318)
						)
						(arc
							(start 0.3302 0.4318)
							(mid 0.402042 0.402042)
							(end 0.4318 0.3302)
						)
						(arc
							(start 0.4318 -0.3302)
							(mid 0.402042 -0.402042)
							(end 0.3302 -0.4318)
						)
					)
					(width 0)
					(fill yes)
				)
			)
		)
		(pad "2" smd custom
			(at 0 0.762 180)
			(size 0.2159 0.2159)
			(layers "F.Cu" "F.Mask" "F.Paste")
			(net "GND")
			(options
				(clearance outline)
				(anchor circle)
			)
			(primitives
				(gr_poly
					(pts
						(arc
							(start -0.3302 -0.4318)
							(mid -0.402042 -0.402042)
							(end -0.4318 -0.3302)
						)
						(arc
							(start -0.4318 0.3302)
							(mid -0.402042 0.402042)
							(end -0.3302 0.4318)
						)
						(arc
							(start 0.3302 0.4318)
							(mid 0.402042 0.402042)
							(end 0.4318 0.3302)
						)
						(arc
							(start 0.4318 -0.3302)
							(mid 0.402042 -0.402042)
							(end 0.3302 -0.4318)
						)
					)
					(width 0)
					(fill yes)
				)
			)
		)
	)
)
